(kicad_pcb
	(version 20221018)
	(generator pcbnew)
	(general
    (thickness 1.7403)
  )
	(paper "A4")
	(title_block
    (title "Data Center RDIMM DDR4 Tester")
    (date "2024-09-30")
    (rev "1.2.4")
		(comment 9 "footprints 275-284 of 690")
	)
	(layers
    (0 "F.Cu" signal)
    (1 "In1.Cu" power)
    (2 "In2.Cu" signal)
    (3 "In3.Cu" power)
    (4 "In4.Cu" power)
    (5 "In5.Cu" signal)
    (6 "In6.Cu" power)
    (7 "In7.Cu" signal)
    (8 "In8.Cu" power)
    (9 "In9.Cu" signal)
    (10 "In10.Cu" power)
    (31 "B.Cu" signal)
    (32 "B.Adhes" user "B.Adhesive")
    (33 "F.Adhes" user "F.Adhesive")
    (34 "B.Paste" user)
    (35 "F.Paste" user)
    (36 "B.SilkS" user "B.Silkscreen")
    (37 "F.SilkS" user "F.Silkscreen")
    (38 "B.Mask" user)
    (39 "F.Mask" user)
    (40 "Dwgs.User" user "User.Drawings")
    (41 "Cmts.User" user "User.Comments")
    (42 "Eco1.User" user "User.Eco1")
    (43 "Eco2.User" user "User.Eco2")
    (44 "Edge.Cuts" user)
    (45 "Margin" user)
    (46 "B.CrtYd" user "B.Courtyard")
    (47 "F.CrtYd" user "F.Courtyard")
    (48 "B.Fab" user)
    (49 "F.Fab" user)
  )
	(footprint "data-center-rdimm-ddr4-tester-footprints:R_0201" (layer "F.Cu")
    (at 160.8 109.03 -90)
    (descr "Resistor SMD 0201")
    (tags "resistor SMD 0201")
    (property "Author" "Antmicro")
    (property "License" "Apache-2.0")
    (property "MPN" "CR0201-FX-0R00GLF")
    (property "Manufacturer" "Bourns")
    (property "Sheetfile" "ethernet.kicad_sch")
    (property "Sheetname" "Ethernet")
    (property "Tolerance" "1%")
    (property "Val" "0R")
    (property "ki_description" "0R resistor in 0201 package with 1% tolerance")
    (attr smd)
    (fp_text reference "R109" (at 3.47 -0.37 -90) (layer "F.SilkS")
        (effects (font (size 0.7 0.7) (thickness 0.15)) (justify left bottom))
    )
    (fp_text value "R_0R_0201" (at 0 1.25 -90) (layer "F.Fab") hide
        (effects (font (size 0.7 0.7) (thickness 0.15)) (justify left bottom))
    )
    (fp_text user "License: Apache-2.0" (at -0.71 4.25 -90) (layer "F.Fab") hide
        (effects (font (size 0.7 0.7) (thickness 0.15)) (justify left bottom))
    )
    (fp_text user "Author: Antmicro" (at -0.71 5.25 -90) (layer "F.Fab") hide
        (effects (font (size 0.7 0.7) (thickness 0.15)) (justify left bottom))
    )
    (fp_text user "${REFERENCE}" (at -0.71 3.25 -90) (layer "F.Fab") hide
        (effects (font (size 0.7 0.7) (thickness 0.15)) (justify left bottom))
    )
    (fp_rect (start -0.71 -0.36) (end 0.71 0.36)
      (stroke (width 0.05) (type solid)) (fill none) (layer "F.CrtYd"))
    (fp_rect (start -0.3 -0.15) (end 0.298 0.148)
      (stroke (width 0.15) (type solid)) (fill none) (layer "F.Fab"))
    (pad "" smd roundrect (at -0.346 0 270) (size 0.318 0.36) (layers "F.Paste") (roundrect_rratio 0.25))
    (pad "" smd roundrect (at 0.344 0 270) (size 0.318 0.36) (layers "F.Paste") (roundrect_rratio 0.25))
    (pad "1" smd roundrect (at -0.32 0 270) (size 0.46 0.4) (layers "F.Cu" "F.Mask") (roundrect_rratio 0.25)
      (net 828 "/Ethernet/ETH3_BP_P") (pintype "passive"))
    (pad "2" smd roundrect (at 0.32 0 270) (size 0.46 0.4) (layers "F.Cu" "F.Mask") (roundrect_rratio 0.25)
      (net 559 "/Ethernet/INT_ETH3_P") (pintype "passive"))
  )
	(footprint "data-center-rdimm-ddr4-tester-footprints:C_0402_1005Metric" (layer "F.Cu")
    (at 232.1 122.4 -90)
    (descr "Capacitor SMD 0402")
    (tags "capacitor SMD 0402")
    (property "Author" "Antmicro")
    (property "Dielectric" "X5R")
    (property "License" "Apache-2.0")
    (property "MPN" "GRM155R61H104KE14D")
    (property "Manufacturer" "Murata")
    (property "Sheetfile" "supply.kicad_sch")
    (property "Sheetname" "Supply")
    (property "Val" "100n")
    (property "Voltage" "50V")
    (property "ki_description" " ")
    (attr smd)
    (fp_text reference "C283" (at 1.54 -1.25 -90) (layer "F.SilkS")
        (effects (font (size 0.7 0.7) (thickness 0.15)) (justify left bottom))
    )
    (fp_text value "C_100n_0402" (at 0 1.4 -90) (layer "F.Fab") hide
        (effects (font (size 0.7 0.7) (thickness 0.15)) (justify left bottom))
    )
    (fp_text user "Author: Antmicro" (at -0.932 4.17 -90) (layer "F.Fab") hide
        (effects (font (size 0.7 0.7) (thickness 0.15)) (justify left bottom))
    )
    (fp_text user "${REFERENCE}" (at -0.932 3.168 -90) (layer "F.Fab") hide
        (effects (font (size 0.7 0.7) (thickness 0.15)) (justify left bottom))
    )
    (fp_text user "License: Apache-2.0" (at -0.932 5.17 -90) (layer "F.Fab") hide
        (effects (font (size 0.7 0.7) (thickness 0.15)) (justify left bottom))
    )
    (fp_rect (start -0.94 -0.47) (end 0.94 0.47)
      (stroke (width 0.05) (type solid)) (fill none) (layer "F.CrtYd"))
    (fp_rect (start -0.499 -0.249) (end 0.499 0.249)
      (stroke (width 0.15) (type solid)) (fill none) (layer "F.Fab"))
    (pad "1" smd roundrect (at -0.484 0 270) (size 0.59 0.64) (layers "F.Cu" "F.Paste" "F.Mask") (roundrect_rratio 0.25)
      (net 846 "5V_ON_OFF") (pintype "passive"))
    (pad "2" smd roundrect (at 0.484 0 270) (size 0.59 0.64) (layers "F.Cu" "F.Paste" "F.Mask") (roundrect_rratio 0.25)
      (net 9 "GND") (pintype "passive"))
  )
	(footprint "data-center-rdimm-ddr4-tester-footprints:R_0201" (layer "F.Cu")
    (at 161.075 104.29 -90)
    (descr "Resistor SMD 0201")
    (tags "resistor SMD 0201")
    (property "Author" "Antmicro")
    (property "License" "Apache-2.0")
    (property "MPN" "CR0201-FX-0R00GLF")
    (property "Manufacturer" "Bourns")
    (property "Sheetfile" "ethernet.kicad_sch")
    (property "Sheetname" "Ethernet")
    (property "Tolerance" "1%")
    (property "Val" "0R")
    (property "ki_description" "0R resistor in 0201 package with 1% tolerance")
    (attr smd)
    (fp_text reference "R103" (at -0.61 -0.435 -90) (layer "F.SilkS")
        (effects (font (size 0.7 0.7) (thickness 0.15)) (justify left bottom))
    )
    (fp_text value "R_0R_0201" (at 0 1.25 -90) (layer "F.Fab") hide
        (effects (font (size 0.7 0.7) (thickness 0.15)) (justify left bottom))
    )
    (fp_text user "Author: Antmicro" (at -0.71 5.25 -90) (layer "F.Fab") hide
        (effects (font (size 0.7 0.7) (thickness 0.15)) (justify left bottom))
    )
    (fp_text user "License: Apache-2.0" (at -0.71 4.25 -90) (layer "F.Fab") hide
        (effects (font (size 0.7 0.7) (thickness 0.15)) (justify left bottom))
    )
    (fp_text user "${REFERENCE}" (at -0.71 3.25 -90) (layer "F.Fab") hide
        (effects (font (size 0.7 0.7) (thickness 0.15)) (justify left bottom))
    )
    (fp_rect (start -0.71 -0.36) (end 0.71 0.36)
      (stroke (width 0.05) (type solid)) (fill none) (layer "F.CrtYd"))
    (fp_rect (start -0.3 -0.15) (end 0.298 0.148)
      (stroke (width 0.15) (type solid)) (fill none) (layer "F.Fab"))
    (pad "" smd roundrect (at -0.346 0 270) (size 0.318 0.36) (layers "F.Paste") (roundrect_rratio 0.25))
    (pad "" smd roundrect (at 0.344 0 270) (size 0.318 0.36) (layers "F.Paste") (roundrect_rratio 0.25))
    (pad "1" smd roundrect (at -0.32 0 270) (size 0.46 0.4) (layers "F.Cu" "F.Mask") (roundrect_rratio 0.25)
      (net 171 "/Ethernet/ETH4_P") (pintype "passive"))
    (pad "2" smd roundrect (at 0.32 0 270) (size 0.46 0.4) (layers "F.Cu" "F.Mask") (roundrect_rratio 0.25)
      (net 830 "/Ethernet/ETH4_BP_P") (pintype "passive"))
  )
	(footprint "data-center-rdimm-ddr4-tester-footprints:R_0402_1005Metric" (layer "F.Cu")
    (at 238.3 123.8 90)
    (descr "Resistor SMD 0402")
    (tags "resistor SMD 0402")
    (property "Author" "Antmicro")
    (property "DNP" "DNP")
    (property "License" "Apache-2.0")
    (property "MPN" "CR0402-FX-4702GLF")
    (property "Manufacturer" "Bourns")
    (property "Sheetfile" "supply.kicad_sch")
    (property "Sheetname" "Supply")
    (property "Tolerance" "1%")
    (property "Val" "47k")
    (property "dnp" "")
    (property "exclude_from_bom" "")
    (property "ki_description" "47k resistor in 0402 package with 1% tolerance")
    (attr exclude_from_pos_files exclude_from_bom)
    (fp_text reference "R117" (at -2.99 1.34 90) (layer "F.SilkS")
        (effects (font (size 0.7 0.7) (thickness 0.15)) (justify left bottom))
    )
    (fp_text value "R_47k_0402" (at 0 1.4 90) (layer "F.Fab") hide
        (effects (font (size 0.7 0.7) (thickness 0.15)) (justify left bottom))
    )
    (fp_text user "${REFERENCE}" (at -0.95 3.168 90) (layer "F.Fab") hide
        (effects (font (size 0.7 0.7) (thickness 0.15)) (justify left bottom))
    )
    (fp_text user "License: Apache-2.0" (at -0.95 5.169 90) (layer "F.Fab") hide
        (effects (font (size 0.7 0.7) (thickness 0.15)) (justify left bottom))
    )
    (fp_text user "Author: Antmicro" (at -0.95 4.169 90) (layer "F.Fab") hide
        (effects (font (size 0.7 0.7) (thickness 0.15)) (justify left bottom))
    )
    (fp_rect (start -0.93 -0.47) (end 0.93 0.47)
      (stroke (width 0.05) (type solid)) (fill none) (layer "F.CrtYd"))
    (fp_rect (start -0.5 -0.25) (end 0.5 0.25)
      (stroke (width 0.15) (type solid)) (fill none) (layer "F.Fab"))
    (pad "1" smd roundrect (at -0.485 0 90) (size 0.59 0.64) (layers "F.Cu" "F.Paste" "F.Mask") (roundrect_rratio 0.25)
      (net 626 "VIN_RAW") (pintype "passive"))
    (pad "2" smd roundrect (at 0.485 0 90) (size 0.59 0.64) (layers "F.Cu" "F.Paste" "F.Mask") (roundrect_rratio 0.25)
      (net 108 "Net-(U27-~{OE})") (pintype "passive"))
  )
	(footprint "data-center-rdimm-ddr4-tester-footprints:NetTie-2_SMD_Pad0.127mm" (layer "F.Cu")
    (at 111.38 108.95 180)
    (descr "Net tie, 2 pin, 0.127mm  SMD pads")
    (tags "net tie")
    (property "Author" "Antmicro")
    (property "License" "Apache-2.0")
    (property "MPN" "")
    (property "Manufacturer" "")
    (property "Sheetfile" "supply.kicad_sch")
    (property "Sheetname" "Supply")
    (property "ki_description" "Net tie, 2 pins")
    (property "ki_keywords" "net tie short")
    (attr through_hole exclude_from_pos_files)
    (net_tie_pad_groups "1, 2")
    (fp_text reference "NT12" (at -0.128 -1.345 180) (layer "F.SilkS") hide
        (effects (font (size 0.7 0.7) (thickness 0.15)) (justify left bottom))
    )
    (fp_text value "Net-Tie_2" (at 0 1.199 180) (layer "F.Fab") hide
        (effects (font (size 0.7 0.7) (thickness 0.15)) (justify left bottom))
    )
    (fp_text user "Author: Antmicro" (at -0.128 4.4 180) (layer "F.Fab") hide
        (effects (font (size 0.7 0.7) (thickness 0.15)) (justify left bottom))
    )
    (fp_text user "${REFERENCE}" (at -0.128 3.2 180) (layer "F.Fab") hide
        (effects (font (size 0.7 0.7) (thickness 0.15)) (justify left bottom))
    )
    (fp_text user "License: Apache-2.0" (at -0.128 5.6 180) (layer "F.Fab") hide
        (effects (font (size 0.7 0.7) (thickness 0.15)) (justify left bottom))
    )
    (fp_poly
      (pts
        (xy -0.0635 -0.0635)
        (xy 0.0625 -0.0635)
        (xy 0.0625 0.0635)
        (xy -0.0635 0.0635)
      )

      (stroke (width 0) (type solid)) (fill solid) (layer "F.Cu"))
    (pad "1" smd roundrect (at -0.127 0) (size 0.127 0.127) (layers "F.Cu") (roundrect_rratio 0.5)
      (chamfer_ratio 0) (chamfer top_left bottom_left)
      (net 843 "/Supply/3V3_SEN_-") (pinfunction "1") (pintype "passive"))
    (pad "2" smd roundrect (at 0.126 0 180) (size 0.127 0.127) (layers "F.Cu") (roundrect_rratio 0.5)
      (chamfer_ratio 0) (chamfer top_left bottom_left)
      (net 143 "3V3_SYS") (pinfunction "2") (pintype "passive"))
  )
	(footprint "data-center-rdimm-ddr4-tester-footprints:R_0402_1005Metric" (layer "F.Cu")
    (at 150.6 127.5 90)
    (descr "Resistor SMD 0402")
    (tags "resistor SMD 0402")
    (property "Author" "Antmicro")
    (property "License" "Apache-2.0")
    (property "MPN" "CR0402-FX-5111GLF")
    (property "Manufacturer" "Bourns")
    (property "Sheetfile" "interfaces.kicad_sch")
    (property "Sheetname" "Interfaces")
    (property "Tolerance" "1%")
    (property "Val" "5k11")
    (property "ki_description" "5k11 resistor in 0402 package with 1% tolerance")
    (attr smd)
    (fp_text reference "R16" (at -0.94 1.17 90) (layer "F.SilkS")
        (effects (font (size 0.7 0.7) (thickness 0.15)) (justify left bottom))
    )
    (fp_text value "R_5k11_0402" (at 0 1.4 90) (layer "F.Fab") hide
        (effects (font (size 0.7 0.7) (thickness 0.15)) (justify left bottom))
    )
    (fp_text user "Author: Antmicro" (at -0.95 4.169 90) (layer "F.Fab") hide
        (effects (font (size 0.7 0.7) (thickness 0.15)) (justify left bottom))
    )
    (fp_text user "License: Apache-2.0" (at -0.95 5.169 90) (layer "F.Fab") hide
        (effects (font (size 0.7 0.7) (thickness 0.15)) (justify left bottom))
    )
    (fp_text user "${REFERENCE}" (at -0.95 3.168 90) (layer "F.Fab") hide
        (effects (font (size 0.7 0.7) (thickness 0.15)) (justify left bottom))
    )
    (fp_rect (start -0.93 -0.47) (end 0.93 0.47)
      (stroke (width 0.05) (type solid)) (fill none) (layer "F.CrtYd"))
    (fp_rect (start -0.5 -0.25) (end 0.5 0.25)
      (stroke (width 0.15) (type solid)) (fill none) (layer "F.Fab"))
    (pad "1" smd roundrect (at -0.485 0 90) (size 0.59 0.64) (layers "F.Cu" "F.Paste" "F.Mask") (roundrect_rratio 0.25)
      (net 569 "Net-(J9-CC2)") (pintype "passive"))
    (pad "2" smd roundrect (at 0.485 0 90) (size 0.59 0.64) (layers "F.Cu" "F.Paste" "F.Mask") (roundrect_rratio 0.25)
      (net 9 "GND") (pintype "passive"))
  )
	(footprint "data-center-rdimm-ddr4-tester-footprints:C_0402_1005Metric" (layer "F.Cu")
    (at 256.18 85.261)
    (descr "Capacitor SMD 0402")
    (tags "capacitor SMD 0402")
    (property "Author" "Antmicro")
    (property "Dielectric" "X5R")
    (property "License" "Apache-2.0")
    (property "MPN" "GRM155R61H104KE14D")
    (property "Manufacturer" "Murata")
    (property "Sheetfile" "fmc_hpc.kicad_sch")
    (property "Sheetname" "FMC HPC")
    (property "Val" "100n")
    (property "Voltage" "50V")
    (property "ki_description" " ")
    (attr smd)
    (fp_text reference "C273" (at 0.69 0.409) (layer "F.SilkS")
        (effects (font (size 0.7 0.7) (thickness 0.15)) (justify left bottom))
    )
    (fp_text value "C_100n_0402" (at 0 1.4) (layer "F.Fab") hide
        (effects (font (size 0.7 0.7) (thickness 0.15)) (justify left bottom))
    )
    (fp_text user "${REFERENCE}" (at -0.932 3.168) (layer "F.Fab") hide
        (effects (font (size 0.7 0.7) (thickness 0.15)) (justify left bottom))
    )
    (fp_text user "License: Apache-2.0" (at -0.932 5.17) (layer "F.Fab") hide
        (effects (font (size 0.7 0.7) (thickness 0.15)) (justify left bottom))
    )
    (fp_text user "Author: Antmicro" (at -0.932 4.17) (layer "F.Fab") hide
        (effects (font (size 0.7 0.7) (thickness 0.15)) (justify left bottom))
    )
    (fp_rect (start -0.94 -0.47) (end 0.94 0.47)
      (stroke (width 0.05) (type solid)) (fill none) (layer "F.CrtYd"))
    (fp_rect (start -0.499 -0.249) (end 0.499 0.249)
      (stroke (width 0.15) (type solid)) (fill none) (layer "F.Fab"))
    (pad "1" smd roundrect (at -0.484 0) (size 0.59 0.64) (layers "F.Cu" "F.Paste" "F.Mask") (roundrect_rratio 0.25)
      (net 513 "/FMC HPC/GTX_TX7_C_P") (pintype "passive"))
    (pad "2" smd roundrect (at 0.484 0) (size 0.59 0.64) (layers "F.Cu" "F.Paste" "F.Mask") (roundrect_rratio 0.25)
      (net 524 "GTX_TX7_P") (pintype "passive"))
  )
	(footprint "data-center-rdimm-ddr4-tester-footprints:SW_DS04-254-1-01BK-SMT" (layer "F.Cu")
    (at 222.225 79.13 180)
    (property "Author" "Antmicro")
    (property "License" "Apache-2.0")
    (property "MPN" "DS04-254-1-01BK-SMT")
    (property "Manufacturer" "CUI Inc")
    (property "Sheetfile" "config-spi.kicad_sch")
    (property "Sheetname" "Config SPI flash")
    (property "ki_description" "Slide switch")
    (property "ki_keywords" "HORIZONTAL, SMT, SWITCH, MECHANICAL, SLIDE")
    (attr smd)
    (fp_text reference "S2" (at 3.485 2.25) (layer "F.SilkS")
        (effects (font (size 0.7 0.7) (thickness 0.15)) (justify left bottom))
    )
    (fp_text value "SW_DS04-254-1-01BK-SMT" (at 0 3) (layer "F.Fab")
        (effects (font (size 0.7 0.7) (thickness 0.15)) (justify right bottom))
    )
    (fp_text user "Author: Antmicro" (at -5.25 5.6) (layer "F.Fab") hide
        (effects (font (size 0.7 0.7) (thickness 0.15)) (justify right bottom))
    )
    (fp_text user "License: Apache-2.0" (at -5.25 6.799) (layer "F.Fab") hide
        (effects (font (size 0.7 0.7) (thickness 0.15)) (justify right bottom))
    )
    (fp_text user "${REFERENCE}" (at -5.25 4.4) (layer "F.Fab") hide
        (effects (font (size 0.7 0.7) (thickness 0.15)) (justify right bottom))
    )
    (fp_rect (start -3.3 -2) (end 3.3 2)
      (stroke (width 0.15) (type solid)) (fill none) (layer "F.SilkS"))
    (fp_rect (start -5.25 -2.025) (end 5.25 2.025)
      (stroke (width 0.05) (type solid)) (fill none) (layer "F.CrtYd"))
    (fp_rect (start -3.1 -1.8) (end 3.1 1.8)
      (stroke (width 0.15) (type solid)) (fill none) (layer "F.Fab"))
    (pad "1" smd rect (at -4.472 0.038 180) (size 1.5 1.1) (layers "F.Cu" "F.Paste" "F.Mask")
      (net 18 "MODE2") (pintype "passive"))
    (pad "2" smd rect (at 4.428 0.038) (size 1.5 1.1) (layers "F.Cu" "F.Paste" "F.Mask")
      (net 9 "GND") (pintype "passive"))
  )
	(footprint "data-center-rdimm-ddr4-tester-footprints:R_0201" (layer "F.Cu")
    (at 156.05 109.03 90)
    (descr "Resistor SMD 0201")
    (tags "resistor SMD 0201")
    (property "Author" "Antmicro")
    (property "License" "Apache-2.0")
    (property "MPN" "CR0201-FX-0R00GLF")
    (property "Manufacturer" "Bourns")
    (property "Sheetfile" "ethernet.kicad_sch")
    (property "Sheetname" "Ethernet")
    (property "Tolerance" "1%")
    (property "Val" "0R")
    (property "ki_description" "0R resistor in 0201 package with 1% tolerance")
    (attr smd)
    (fp_text reference "R106" (at -3.48 0.37 90) (layer "F.SilkS")
        (effects (font (size 0.7 0.7) (thickness 0.15)) (justify left bottom))
    )
    (fp_text value "R_0R_0201" (at 0 1.25 90) (layer "F.Fab") hide
        (effects (font (size 0.7 0.7) (thickness 0.15)) (justify left bottom))
    )
    (fp_text user "License: Apache-2.0" (at -0.71 4.25 90) (layer "F.Fab") hide
        (effects (font (size 0.7 0.7) (thickness 0.15)) (justify left bottom))
    )
    (fp_text user "${REFERENCE}" (at -0.71 3.25 90) (layer "F.Fab") hide
        (effects (font (size 0.7 0.7) (thickness 0.15)) (justify left bottom))
    )
    (fp_text user "Author: Antmicro" (at -0.71 5.25 90) (layer "F.Fab") hide
        (effects (font (size 0.7 0.7) (thickness 0.15)) (justify left bottom))
    )
    (fp_rect (start -0.71 -0.36) (end 0.71 0.36)
      (stroke (width 0.05) (type solid)) (fill none) (layer "F.CrtYd"))
    (fp_rect (start -0.3 -0.15) (end 0.298 0.148)
      (stroke (width 0.15) (type solid)) (fill none) (layer "F.Fab"))
    (pad "" smd roundrect (at -0.346 0 90) (size 0.318 0.36) (layers "F.Paste") (roundrect_rratio 0.25))
    (pad "" smd roundrect (at 0.344 0 90) (size 0.318 0.36) (layers "F.Paste") (roundrect_rratio 0.25))
    (pad "1" smd roundrect (at -0.32 0 90) (size 0.46 0.4) (layers "F.Cu" "F.Mask") (roundrect_rratio 0.25)
      (net 630 "/Ethernet/INT_ETH1_N") (pintype "passive"))
    (pad "2" smd roundrect (at 0.32 0 90) (size 0.46 0.4) (layers "F.Cu" "F.Mask") (roundrect_rratio 0.25)
      (net 825 "/Ethernet/ETH1_BP_N") (pintype "passive"))
  )
	(footprint "data-center-rdimm-ddr4-tester-footprints:NetTie-2_SMD_Pad0.127mm" (layer "F.Cu")
    (at 130.7 84.234 -90)
    (descr "Net tie, 2 pin, 0.127mm  SMD pads")
    (tags "net tie")
    (property "Author" "Antmicro")
    (property "License" "Apache-2.0")
    (property "MPN" "")
    (property "Manufacturer" "")
    (property "Sheetfile" "supply.kicad_sch")
    (property "Sheetname" "Supply")
    (property "ki_description" "Net tie, 2 pins")
    (property "ki_keywords" "net tie short")
    (attr through_hole exclude_from_pos_files)
    (net_tie_pad_groups "1, 2")
    (fp_text reference "NT9" (at -0.128 -1.345 -90) (layer "F.SilkS") hide
        (effects (font (size 0.7 0.7) (thickness 0.15)) (justify left bottom))
    )
    (fp_text value "Net-Tie_2" (at 0 1.199 -90) (layer "F.Fab") hide
        (effects (font (size 0.7 0.7) (thickness 0.15)) (justify left bottom))
    )
    (fp_text user "Author: Antmicro" (at -0.128 4.4 -90) (layer "F.Fab") hide
        (effects (font (size 0.7 0.7) (thickness 0.15)) (justify left bottom))
    )
    (fp_text user "${REFERENCE}" (at -0.128 3.2 -90) (layer "F.Fab") hide
        (effects (font (size 0.7 0.7) (thickness 0.15)) (justify left bottom))
    )
    (fp_text user "License: Apache-2.0" (at -0.128 5.6 -90) (layer "F.Fab") hide
        (effects (font (size 0.7 0.7) (thickness 0.15)) (justify left bottom))
    )
    (fp_poly
      (pts
        (xy -0.0635 -0.0635)
        (xy 0.0625 -0.0635)
        (xy 0.0625 0.0635)
        (xy -0.0635 0.0635)
      )

      (stroke (width 0) (type solid)) (fill solid) (layer "F.Cu"))
    (pad "1" smd roundrect (at -0.127 0 90) (size 0.127 0.127) (layers "F.Cu") (roundrect_rratio 0.5)
      (chamfer_ratio 0) (chamfer top_left bottom_left)
      (net 840 "/Supply/1V8_SEN_+") (pinfunction "1") (pintype "passive"))
    (pad "2" smd roundrect (at 0.126 0 270) (size 0.127 0.127) (layers "F.Cu") (roundrect_rratio 0.5)
      (chamfer_ratio 0) (chamfer top_left bottom_left)
      (net 302 "VCC1V8") (pinfunction "2") (pintype "passive"))
  )
)
